# S9S_MB_2U (Grand Teton) — schematic netlist excerpt (pin names and nets, part order shuffled) for the footprints in the layout excerpt that follows; sources: Cadence DE-HDL packaged netlist, KiCad conversion of 03242023_DA0F0TMBIJ0_F0T_Motherboard_J_brd_V01_OCP.brd

R1389  Q_RES  0 5% CHIP  pkg 0402LF  page 262 : A = FM_P1V05_PCH_AUX_EN ; B = FM_P1V05_PCH_AUX_R_EN
C421  Q_CAP  22UF 4V 20% X6S  pkg C0402  page 74 : A = PVCCFA_EHV_CPU0 ; B = GND

(kicad_pcb
	(version 20260206)
	(generator "pcbnew")
	(generator_version "10.0")
	(general
		(thickness 1.6)
		(legacy_teardrops no)
	)
	(paper "A4")
	(title_block
		(title "03242023_DA0F0TMBIJ0_F0T_Motherboard_J_brd_V01_OCP.brd")
		(comment 1 "Grand Teton / footprints 3459-3460 of 6105")
	)
	(layers
		(0 "F.Cu" signal "TOP")
		(4 "In1.Cu" signal "GND")
		(6 "In2.Cu" signal "IN1")
		(8 "In3.Cu" signal "GND1")
		(10 "In4.Cu" signal "IN2")
		(12 "In5.Cu" signal "GND2")
		(14 "In6.Cu" signal "IN3")
		(16 "In7.Cu" signal "GND3")
		(18 "In8.Cu" signal "VCC")
		(20 "In9.Cu" signal "VCC1")
		(22 "In10.Cu" signal "GND4")
		(24 "In11.Cu" signal "IN4")
		(26 "In12.Cu" signal "GND5")
		(28 "In13.Cu" signal "IN5")
		(30 "In14.Cu" signal "GND6")
		(32 "In15.Cu" signal "IN6")
		(34 "In16.Cu" signal "GND7")
		(2 "B.Cu" signal "BOTTOM")
		(9 "F.Adhes" user "F.Adhesive")
		(11 "B.Adhes" user "B.Adhesive")
		(13 "F.Paste" user "Package Geometry/Pastemask Top")
		(15 "B.Paste" user "Package Geometry/Pastemask Bottom")
		(5 "F.SilkS" user "Ref Des/Silkscreen Top")
		(7 "B.SilkS" user "Ref Des/Silkscreen Bottom")
		(1 "F.Mask" user "Board Geometry/Soldermask Top")
		(3 "B.Mask" user "Board Geometry/Soldermask Bottom")
		(17 "Dwgs.User" user "User.Drawings")
		(19 "Cmts.User" user "User.Comments")
		(21 "Eco1.User" user "User.Eco1")
		(23 "Eco2.User" user "User.Eco2")
		(25 "Edge.Cuts" user "Board Geometry/Outline")
		(27 "Margin" user)
		(31 "F.CrtYd" user "Package Geometry/Place Bound Top")
		(29 "B.CrtYd" user "Package Geometry/Place Bound Bottom")
		(35 "F.Fab" user "Ref Des/Assembly Top")
		(33 "B.Fab" user "Ref Des/Assembly Bottom")
	)
	(footprint ""
		(layer "F.Cu")
		(at 352.270314 -256.654046 -90)
		(property "Reference" "C421"
			(at 0 0 270)
			(layer "F.SilkS")
			(hide yes)
			(effects
				(font
					(size 1.27 1.27)
				)
			)
		)
		(property "Value" ""
			(at 0 0 270)
			(layer "F.Fab")
			(effects
				(font
					(size 1.27 1.27)
				)
			)
		)
		(duplicate_pad_numbers_are_jumpers no)
		(fp_line
			(start -0.7874 0.4064)
			(end -0.7874 -0.4064)
			(stroke
				(width 0.1524)
				(type default)
			)
			(layer "F.SilkS")
		)
		(fp_line
			(start 0.7874 0.4064)
			(end -0.7874 0.4064)
			(stroke
				(width 0.1524)
				(type default)
			)
			(layer "F.SilkS")
		)
		(fp_line
			(start -0.7874 -0.4064)
			(end 0.7874 -0.4064)
			(stroke
				(width 0.1524)
				(type default)
			)
			(layer "F.SilkS")
		)
		(fp_line
			(start 0.7874 -0.4064)
			(end 0.7874 0.4064)
			(stroke
				(width 0.1524)
				(type default)
			)
			(layer "F.SilkS")
		)
		(fp_line
			(start -0.67945 0.3048)
			(end -0.67945 -0.305054)
			(stroke
				(width 0.1)
				(type default)
			)
			(layer "F.Fab")
		)
		(fp_line
			(start -0.12065 0.3048)
			(end -0.67945 0.3048)
			(stroke
				(width 0.1)
				(type default)
			)
			(layer "F.Fab")
		)
		(fp_line
			(start 0.120396 0.3048)
			(end 0.120396 0.2794)
			(stroke
				(width 0.1)
				(type default)
			)
			(layer "F.Fab")
		)
		(fp_line
			(start 0.67945 0.3048)
			(end 0.120396 0.3048)
			(stroke
				(width 0.1)
				(type default)
			)
			(layer "F.Fab")
		)
		(fp_line
			(start -0.12065 0.2794)
			(end -0.12065 0.3048)
			(stroke
				(width 0.1)
				(type default)
			)
			(layer "F.Fab")
		)
		(fp_line
			(start 0.120396 0.2794)
			(end -0.12065 0.2794)
			(stroke
				(width 0.1)
				(type default)
			)
			(layer "F.Fab")
		)
		(fp_line
			(start -0.12065 -0.2794)
			(end 0.12065 -0.2794)
			(stroke
				(width 0.1)
				(type default)
			)
			(layer "F.Fab")
		)
		(fp_line
			(start 0.12065 -0.2794)
			(end 0.12065 -0.3048)
			(stroke
				(width 0.1)
				(type default)
			)
			(layer "F.Fab")
		)
		(fp_line
			(start 0.12065 -0.3048)
			(end 0.67945 -0.3048)
			(stroke
				(width 0.1)
				(type default)
			)
			(layer "F.Fab")
		)
		(fp_line
			(start 0.67945 -0.3048)
			(end 0.67945 0.3048)
			(stroke
				(width 0.1)
				(type default)
			)
			(layer "F.Fab")
		)
		(fp_line
			(start -0.67945 -0.305054)
			(end -0.12065 -0.305054)
			(stroke
				(width 0.1)
				(type default)
			)
			(layer "F.Fab")
		)
		(fp_line
			(start -0.12065 -0.305054)
			(end -0.12065 -0.2794)
			(stroke
				(width 0.1)
				(type default)
			)
			(layer "F.Fab")
		)
		(pad "1" smd circle
			(at -0.40005 0 270)
			(size 0 0)
			(layers "F.Cu" "F.Mask" "F.Paste")
			(net "PVCCFA_EHV_CPU0")
		)
		(pad "2" smd circle
			(at 0.40005 0 270)
			(size 0 0)
			(layers "F.Cu" "F.Mask" "F.Paste")
			(net "GND")
		)
	)
	(footprint ""
		(layer "F.Cu")
		(at 259.064506 -75.923902 -90)
		(property "Reference" "R1389"
			(at 0 0 270)
			(layer "F.SilkS")
			(hide yes)
			(effects
				(font
					(size 1.27 1.27)
				)
			)
		)
		(property "Value" ""
			(at 0 0 270)
			(layer "F.Fab")
			(effects
				(font
					(size 1.27 1.27)
				)
			)
		)
		(duplicate_pad_numbers_are_jumpers no)
		(fp_line
			(start -0.7874 0.4064)
			(end -0.7874 -0.4064)
			(stroke
				(width 0.1524)
				(type default)
			)
			(layer "F.SilkS")
		)
		(fp_line
			(start 0.7874 0.4064)
			(end -0.7874 0.4064)
			(stroke
				(width 0.1524)
				(type default)
			)
			(layer "F.SilkS")
		)
		(fp_line
			(start -0.7874 -0.4064)
			(end 0.7874 -0.4064)
			(stroke
				(width 0.1524)
				(type default)
			)
			(layer "F.SilkS")
		)
		(fp_line
			(start 0.7874 -0.4064)
			(end 0.7874 0.4064)
			(stroke
				(width 0.1524)
				(type default)
			)
			(layer "F.SilkS")
		)
		(fp_line
			(start -0.67945 0.3048)
			(end -0.67945 -0.305054)
			(stroke
				(width 0.1)
				(type default)
			)
			(layer "F.Fab")
		)
		(fp_line
			(start -0.12065 0.3048)
			(end -0.67945 0.3048)
			(stroke
				(width 0.1)
				(type default)
			)
			(layer "F.Fab")
		)
		(fp_line
			(start 0.120396 0.3048)
			(end 0.120396 0.2794)
			(stroke
				(width 0.1)
				(type default)
			)
			(layer "F.Fab")
		)
		(fp_line
			(start 0.67945 0.3048)
			(end 0.120396 0.3048)
			(stroke
				(width 0.1)
				(type default)
			)
			(layer "F.Fab")
		)
		(fp_line
			(start -0.12065 0.2794)
			(end -0.12065 0.3048)
			(stroke
				(width 0.1)
				(type default)
			)
			(layer "F.Fab")
		)
		(fp_line
			(start 0.120396 0.2794)
			(end -0.12065 0.2794)
			(stroke
				(width 0.1)
				(type default)
			)
			(layer "F.Fab")
		)
		(fp_line
			(start -0.12065 -0.2794)
			(end 0.12065 -0.2794)
			(stroke
				(width 0.1)
				(type default)
			)
			(layer "F.Fab")
		)
		(fp_line
			(start 0.12065 -0.2794)
			(end 0.12065 -0.3048)
			(stroke
				(width 0.1)
				(type default)
			)
			(layer "F.Fab")
		)
		(fp_line
			(start 0.12065 -0.3048)
			(end 0.67945 -0.3048)
			(stroke
				(width 0.1)
				(type default)
			)
			(layer "F.Fab")
		)
		(fp_line
			(start 0.67945 -0.3048)
			(end 0.67945 0.3048)
			(stroke
				(width 0.1)
				(type default)
			)
			(layer "F.Fab")
		)
		(fp_line
			(start -0.67945 -0.305054)
			(end -0.12065 -0.305054)
			(stroke
				(width 0.1)
				(type default)
			)
			(layer "F.Fab")
		)
		(fp_line
			(start -0.12065 -0.305054)
			(end -0.12065 -0.2794)
			(stroke
				(width 0.1)
				(type default)
			)
			(layer "F.Fab")
		)
		(pad "1" smd circle
			(at -0.40005 0 270)
			(size 0 0)
			(layers "F.Cu" "F.Mask" "F.Paste")
			(net "FM_P1V05_PCH_AUX_EN")
		)
		(pad "2" smd circle
			(at 0.40005 0 270)
			(size 0 0)
			(layers "F.Cu" "F.Mask" "F.Paste")
			(net "FM_P1V05_PCH_AUX_R_EN")
		)
	)
)
